# T6G (Grand Teton) — schematic netlist excerpt (pin names and nets, part order shuffled) for the footprints in the layout excerpt that follows; sources: Cadence DE-HDL packaged netlist, KiCad conversion of 04192023_DAF0TMB3IC0_F0TG_MB_C_brd_V02_OCP.brd

Q70  MOSFET_NCH_DUAL  PJT138K IC  pkg SOT363XD  page 127
  S1  = GND
  G1  = FM_SWB_BIC_READY_N
  D2  = FM_SWB_BIC_READY_ISO_N
  S2  = GND
  G2  = FM_SWB_BIC_READY
  D1  = FM_SWB_BIC_READY

Q7002  MOSFET_PCH_GDS_ESD_PROTECTED  DMP2035U-7 EMPTY  pkg SOT23_GDSXC  page 169
  D  = P3V3_AUX_DSC_G2
  G  = P3V3_AUX_DSC_G1
  S  = P3V3_AUX_DSC_S1

(kicad_pcb
	(version 20260206)
	(generator "pcbnew")
	(generator_version "10.0")
	(general
		(thickness 1.6)
		(legacy_teardrops no)
	)
	(paper "A4")
	(title_block
		(title "04192023_DAF0TMB3IC0_F0TG_MB_C_brd_V02_OCP.brd")
		(comment 1 "Grand Teton / footprints 4102-4103 of 8354")
	)
	(layers
		(0 "F.Cu" signal "TOP")
		(4 "In1.Cu" signal "GND")
		(6 "In2.Cu" signal "IN1")
		(8 "In3.Cu" signal "GND1")
		(10 "In4.Cu" signal "IN2")
		(12 "In5.Cu" signal "GND2")
		(14 "In6.Cu" signal "IN3")
		(16 "In7.Cu" signal "GND3")
		(18 "In8.Cu" signal "VCC")
		(20 "In9.Cu" signal "VCC1")
		(22 "In10.Cu" signal "GND4")
		(24 "In11.Cu" signal "IN4")
		(26 "In12.Cu" signal "GND5")
		(28 "In13.Cu" signal "IN5")
		(30 "In14.Cu" signal "GND6")
		(32 "In15.Cu" signal "IN6")
		(34 "In16.Cu" signal "GND7")
		(2 "B.Cu" signal "BOTTOM")
		(9 "F.Adhes" user "F.Adhesive")
		(11 "B.Adhes" user "B.Adhesive")
		(13 "F.Paste" user "Package Geometry/Pastemask Top")
		(15 "B.Paste" user "Package Geometry/Pastemask Bottom")
		(5 "F.SilkS" user "Ref Des/Silkscreen Top")
		(7 "B.SilkS" user "Ref Des/Silkscreen Bottom")
		(1 "F.Mask" user "Board Geometry/Soldermask Top")
		(3 "B.Mask" user "Board Geometry/Soldermask Bottom")
		(17 "Dwgs.User" user "User.Drawings")
		(19 "Cmts.User" user "User.Comments")
		(21 "Eco1.User" user "User.Eco1")
		(23 "Eco2.User" user "User.Eco2")
		(25 "Edge.Cuts" user "Board Geometry/Outline")
		(27 "Margin" user)
		(31 "F.CrtYd" user "Package Geometry/Place Bound Top")
		(29 "B.CrtYd" user "Package Geometry/Place Bound Bottom")
		(35 "F.Fab" user "Ref Des/Assembly Top")
		(33 "B.Fab" user "Ref Des/Assembly Bottom")
	)
	(footprint ""
		(layer "F.Cu")
		(at 432.24704 -435.436772)
		(property "Reference" "Q70"
			(at -1.4224 -1.768348 0)
			(unlocked yes)
			(layer "F.SilkS")
			(effects
				(font
					(size 0.7874 0.5842)
					(thickness 0.1524)
				)
				(justify left)
			)
		)
		(property "Value" ""
			(at 0 0 0)
			(layer "F.Fab")
			(effects
				(font
					(size 1.27 1.27)
				)
			)
		)
		(duplicate_pad_numbers_are_jumpers no)
		(fp_line
			(start -1.332738 -1.100074)
			(end -0.4826 -1.100074)
			(stroke
				(width 0.1524)
				(type default)
			)
			(layer "F.SilkS")
		)
		(fp_line
			(start -1.332738 1.100074)
			(end -1.332738 -1.100074)
			(stroke
				(width 0.1524)
				(type default)
			)
			(layer "F.SilkS")
		)
		(fp_line
			(start -0.4826 -1.100074)
			(end 0 -0.541274)
			(stroke
				(width 0.1524)
				(type default)
			)
			(layer "F.SilkS")
		)
		(fp_line
			(start 0 -0.541274)
			(end 0.4826 -1.100074)
			(stroke
				(width 0.1524)
				(type default)
			)
			(layer "F.SilkS")
		)
		(fp_line
			(start 0.4826 -1.100074)
			(end 1.332738 -1.100074)
			(stroke
				(width 0.1524)
				(type default)
			)
			(layer "F.SilkS")
		)
		(fp_line
			(start 1.332738 -1.100074)
			(end 1.332738 1.100074)
			(stroke
				(width 0.1524)
				(type default)
			)
			(layer "F.SilkS")
		)
		(fp_line
			(start 1.332738 1.100074)
			(end -1.332738 1.100074)
			(stroke
				(width 0.1524)
				(type default)
			)
			(layer "F.SilkS")
		)
		(fp_poly
			(pts
				(xy -1.630934 -1.2446) (xy -2.356358 -1.544066) (xy -1.826514 -2.004568)
			)
			(stroke
				(width 0)
				(type default)
			)
			(fill yes)
			(layer "F.SilkS")
		)
		(fp_line
			(start -0.674878 -1.100074)
			(end 0.674878 -1.100074)
			(stroke
				(width 0.1)
				(type default)
			)
			(layer "F.Fab")
		)
		(fp_line
			(start -0.674878 1.100074)
			(end -0.674878 -1.100074)
			(stroke
				(width 0.1)
				(type default)
			)
			(layer "F.Fab")
		)
		(fp_line
			(start 0.674878 -1.100074)
			(end 0.674878 1.100074)
			(stroke
				(width 0.1)
				(type default)
			)
			(layer "F.Fab")
		)
		(fp_line
			(start 0.674878 1.100074)
			(end -0.674878 1.100074)
			(stroke
				(width 0.1)
				(type default)
			)
			(layer "F.Fab")
		)
		(fp_poly
			(pts
				(xy -2.2352 -0.298958) (xy -2.2352 -1.001014) (xy -1.533144 -0.649986)
			)
			(stroke
				(width 0)
				(type default)
			)
			(fill yes)
			(layer "F.Fab")
		)
		(pad "1" smd rect
			(at -0.94996 -0.649986 90)
			(size 0.4318 0.508)
			(layers "F.Cu" "F.Mask" "F.Paste")
			(net "GND")
		)
		(pad "2" smd rect
			(at -0.94996 0 90)
			(size 0.4318 0.508)
			(layers "F.Cu" "F.Mask" "F.Paste")
			(net "FM_SWB_BIC_READY_N")
		)
		(pad "3" smd rect
			(at -0.94996 0.649986 90)
			(size 0.4318 0.508)
			(layers "F.Cu" "F.Mask" "F.Paste")
			(net "FM_SWB_BIC_READY_ISO_N")
		)
		(pad "4" smd rect
			(at 0.94996 0.649986 90)
			(size 0.4318 0.508)
			(layers "F.Cu" "F.Mask" "F.Paste")
			(net "GND")
		)
		(pad "5" smd rect
			(at 0.94996 0 90)
			(size 0.4318 0.508)
			(layers "F.Cu" "F.Mask" "F.Paste")
			(net "FM_SWB_BIC_READY")
		)
		(pad "6" smd rect
			(at 0.94996 -0.649986 90)
			(size 0.4318 0.508)
			(layers "F.Cu" "F.Mask" "F.Paste")
			(net "FM_SWB_BIC_READY")
		)
	)
	(footprint ""
		(layer "F.Cu")
		(at 46.08068 -108.585 90)
		(property "Reference" "Q7002"
			(at -1.651 -2.25933 90)
			(unlocked yes)
			(layer "F.SilkS")
			(effects
				(font
					(size 0.7874 0.5842)
					(thickness 0.1524)
				)
				(justify left)
			)
		)
		(property "Value" ""
			(at 0 0 90)
			(layer "F.Fab")
			(effects
				(font
					(size 1.27 1.27)
				)
			)
		)
		(duplicate_pad_numbers_are_jumpers no)
		(fp_line
			(start 1.603248 -1.500124)
			(end 1.603248 1.500124)
			(stroke
				(width 0.1524)
				(type default)
			)
			(layer "F.SilkS")
		)
		(fp_line
			(start -1.603248 -1.500124)
			(end 1.603248 -1.500124)
			(stroke
				(width 0.1524)
				(type default)
			)
			(layer "F.SilkS")
		)
		(fp_line
			(start 1.603248 1.500124)
			(end -1.603248 1.500124)
			(stroke
				(width 0.1524)
				(type default)
			)
			(layer "F.SilkS")
		)
		(fp_line
			(start -1.603248 1.500124)
			(end -1.603248 -1.500124)
			(stroke
				(width 0.1524)
				(type default)
			)
			(layer "F.SilkS")
		)
		(fp_line
			(start 0.700024 -1.500124)
			(end -0.700024 -1.500124)
			(stroke
				(width 0.1)
				(type default)
			)
			(layer "F.Fab")
		)
		(fp_line
			(start -0.700024 -1.500124)
			(end -0.700024 -1.169924)
			(stroke
				(width 0.1)
				(type default)
			)
			(layer "F.Fab")
		)
		(fp_line
			(start -0.700024 -1.169924)
			(end -1.249934 -1.169924)
			(stroke
				(width 0.1)
				(type default)
			)
			(layer "F.Fab")
		)
		(fp_line
			(start -1.249934 -1.169924)
			(end -1.249934 -0.729996)
			(stroke
				(width 0.1)
				(type default)
			)
			(layer "F.Fab")
		)
		(fp_line
			(start -0.6985 -0.729996)
			(end -0.6985 0.729996)
			(stroke
				(width 0.1)
				(type default)
			)
			(layer "F.Fab")
		)
		(fp_line
			(start -1.249934 -0.729996)
			(end -0.6985 -0.729996)
			(stroke
				(width 0.1)
				(type default)
			)
			(layer "F.Fab")
		)
		(fp_line
			(start 1.249934 -0.219964)
			(end 0.700024 -0.219964)
			(stroke
				(width 0.1)
				(type default)
			)
			(layer "F.Fab")
		)
		(fp_line
			(start 0.700024 -0.219964)
			(end 0.700024 -1.500124)
			(stroke
				(width 0.1)
				(type default)
			)
			(layer "F.Fab")
		)
		(fp_line
			(start 1.249934 0.219964)
			(end 1.249934 -0.219964)
			(stroke
				(width 0.1)
				(type default)
			)
			(layer "F.Fab")
		)
		(fp_line
			(start 0.700024 0.219964)
			(end 1.249934 0.219964)
			(stroke
				(width 0.1)
				(type default)
			)
			(layer "F.Fab")
		)
		(fp_line
			(start -0.6985 0.729996)
			(end -1.249934 0.729996)
			(stroke
				(width 0.1)
				(type default)
			)
			(layer "F.Fab")
		)
		(fp_line
			(start -1.249934 0.729996)
			(end -1.249934 1.169924)
			(stroke
				(width 0.1)
				(type default)
			)
			(layer "F.Fab")
		)
		(fp_line
			(start -0.700024 1.169924)
			(end -0.700024 1.500124)
			(stroke
				(width 0.1)
				(type default)
			)
			(layer "F.Fab")
		)
		(fp_line
			(start -1.249934 1.169924)
			(end -0.700024 1.169924)
			(stroke
				(width 0.1)
				(type default)
			)
			(layer "F.Fab")
		)
		(fp_line
			(start 0.700024 1.500124)
			(end 0.700024 0.219964)
			(stroke
				(width 0.1)
				(type default)
			)
			(layer "F.Fab")
		)
		(fp_line
			(start -0.700024 1.500124)
			(end 0.700024 1.500124)
			(stroke
				(width 0.1)
				(type default)
			)
			(layer "F.Fab")
		)
		(fp_rect
			(start -0.700024 1.500124)
			(end 0.700024 -1.500124)
			(stroke
				(width 0)
				(type default)
			)
			(fill no)
			(layer "F.Fab")
		)
		(pad "D" smd rect
			(at 0.999998 0)
			(size 0.8128 0.9144)
			(layers "F.Cu" "F.Mask" "F.Paste")
			(net "P3V3_AUX_DSC_G2")
		)
		(pad "G" smd rect
			(at -0.999998 -0.94996)
			(size 0.8128 0.9144)
			(layers "F.Cu" "F.Mask" "F.Paste")
			(net "P3V3_AUX_DSC_G1")
		)
		(pad "S" smd rect
			(at -0.999998 0.94996)
			(size 0.8128 0.9144)
			(layers "F.Cu" "F.Mask" "F.Paste")
			(net "P3V3_AUX_DSC_S1")
		)
	)
)
